FILE_TYPE = CONNECTIVITY;
{Allegro Design Entry HDL 17.2-2016 S081 (4005846) 1/11/2022}
"PAGE_NUMBER" = 189;
0"NC";
1"P1V05_PCH_AUX\g";
2"P3V3_AUX\g";
3"P3V3_AUX\g";
4"P1V05_PCH_AUX\g";
5"P3V3_RTC_AUX\g";
6"GND\g";
7"GND\g";
8"GND\g";
9"GND\g";
10"GND\g";
11"GND\g";
12"PU_SWAP_OVERRIDE_N"CDS_PHYS_NET_NAME"PU_SWAP_OVERRIDE_N";
13"PD_ME_RCVR_N"CDS_PHYS_NET_NAME"PD_ME_RCVR_N";
14"PD_PASSWORD_CLEAR"CDS_PHYS_NET_NAME"PD_PASSWORD_CLEAR";
15"PU_FLASH_SECURITY_STRAP"CDS_PHYS_NET_NAME"RST_RTCRST_N";
16"PD_BIOS_IMAGE_SWAP_N"CDS_PHYS_NET_NAME"PD_BIOS_IMAGE_SWAP_N";
17"PU_BIOS_RCVR_BOOT"CDS_PHYS_NET_NAME"PU_BIOS_RCVR_BOOT";
18"PU_ESPI_ENABLE_STRAP"CDS_PHYS_NET_NAME"PU_ESPI_ENABLE_STRAP";
19"FM_PASSWORD_CLEAR_N"CDS_PHYS_NET_NAME"FM_PASSWORD_CLEAR_N";
20"FM_ME_RCVR_N"CDS_PHYS_NET_NAME"FM_ME_RCVR_N";
21"JTAG_TRC_PCH_PTI<6>"CDS_PHYS_NET_NAME"JTAG_TRC_PCH_PTI<6>";
22"FM_PCH_BIOS_RCVR_MODE"CDS_PHYS_NET_NAME"FM_PCH_BIOS_RCVR_MODE";
23"FM_ADR_COMPLETE"CDS_PHYS_NET_NAME"FM_ADR_COMPLETE";
24"FM_BIOS_IMAGE_SWAP_N"CDS_PHYS_NET_NAME"FM_BIOS_IMAGE_SWAP_N";
25"FM_FLASH_SECURITY_STRAP"CDS_PHYS_NET_NAME"FM_FLASH_SECURITY_STRAP";
26"RST_RTCRST_N"CDS_PHYS_NET_NAME"RST_RTCRST_N";
27"PD_RST_RTCRST_N"CDS_PHYS_NET_NAME"RST_RTCRST_N";
%"Q_RES"
"2","(3575,3950)","0","pure_quanta","I100";
;
PART_NUMBER"CS31002FB08"
PACK_TYPE"0402LF"
TOLERANCE"1%"
VALUE"10K"
MATERIAL"CHIP"
WATTAGE"1/16W"
$LOCATION"R1339"
CDS_LIB"pure_quanta"
CDS_LOCATION"R1339"
$SEC"1"
CDS_SEC"1";
"A"
$PN"1"3;
"B"
$PN"2"24;
%"UNIVERSAL_GND"
"1","(3025,2800)","0","logical_power","I105";
;
CDS_LIB"logical_power"
HDL_POWER"GND"
ROOM"IO_SLOT";
"A"7;
%"Q_RES"
"2","(3025,3025)","0","pure_quanta","I106";
;
PART_NUMBER"CS31002FB08"
PACK_TYPE"0402LF"
VALUE"10K"
TOLERANCE"1%"
WATTAGE"1/16W"
MATERIAL"CHIP"
$LOCATION"R1341"
CDS_LIB"pure_quanta"
CDS_LOCATION"R1341"
$SEC"1"
CDS_SEC"1";
"A"
$PN"1"23;
"B"
$PN"2"7;
%"Q_RES"
"2","(2800,3025)","0","pure_quanta","I107";
;
PART_NUMBER"CS31002FB08"
TOLERANCE"1%"
WATTAGE"1/16W"
VALUE"10K"
MATERIAL"CHIP"
PACK_TYPE"0402LF"
$LOCATION"R1338"
CDS_LIB"pure_quanta"
CDS_LOCATION"R1338"
$SEC"1"
CDS_SEC"1";
"A"
$PN"1"22;
"B"
$PN"2"8;
%"UNIVERSAL_GND"
"1","(2800,2800)","0","logical_power","I108";
;
CDS_LIB"logical_power"
HDL_POWER"GND"
ROOM"IO_SLOT";
"A"8;
%"Q_RES"
"2","(2575,3025)","0","pure_quanta","I109";
;
PART_NUMBER"CS31002FB08"
WATTAGE"1/16W"
VALUE"10K"
TOLERANCE"1%"
PACK_TYPE"0402LF"
MATERIAL"CHIP"
$LOCATION"R2134"
CDS_LIB"pure_quanta"
CDS_LOCATION"R2134"
$SEC"1"
CDS_SEC"1";
"A"
$PN"1"21;
"B"
$PN"2"9;
%"UNIVERSAL_GND"
"1","(2575,2800)","0","logical_power","I110";
;
CDS_LIB"logical_power"
HDL_POWER"GND"
ROOM"IO_SLOT";
"A"9;
%"UNIVERSAL_POWER"
"1","(4000,4275)","0","logical_power","I112";
;
HDL_POWER"P1V05_PCH_AUX"
CDS_LIB"logical_power";
"A"4;
%"Q_RES"
"2","(4000,3950)","0","pure_quanta","I113";
;
PART_NUMBER"CS31002FB08"
TOLERANCE"1%"
VALUE"10K"
WATTAGE"1/16W"
MATERIAL"CHIP"
PACK_TYPE"0402LF"
$LOCATION"R1343"
CDS_LIB"pure_quanta"
CDS_LOCATION"R1343"
$SEC"1"
CDS_SEC"1";
"A"
$PN"1"4;
"B"
$PN"2"19;
%"Q_RES"
"2","(4250,3950)","0","pure_quanta","I114";
;
PART_NUMBER"CS31002FB08"
PACK_TYPE"0402LF"
TOLERANCE"1%"
WATTAGE"1/16W"
VALUE"10K"
MATERIAL"CHIP"
$LOCATION"R1342"
CDS_LIB"pure_quanta"
CDS_LOCATION"R1342"
$SEC"1"
CDS_SEC"1";
"A"
$PN"1"4;
"B"
$PN"2"20;
%"SW_PUSHBUTTON4P_24"
"1","(1150,1550)","0","pure_quanta","I122";
;
PART_NUMBER"DHP00061N15"
VALUE"SW4S_DTSM-61N-S-Q-T/R"
MATERIAL"MECH"
PART_TYPE"SMLF"
$LOCATION"SW5"
NEEDS_NO_SIZE"TRUE"
CDS_LIB"pure_quanta"
CDS_LMAN_SYM_OUTLINE"-75,100,75,-100"
CDS_LOCATION"SW5"
$SEC"1"
CDS_SEC"1";
"4"
$PN"4"26;
"3"
$PN"3"26;
"2"
$PN"2"27;
"1"
$PN"1"27;
%"Q_RES"
"1","(-550,1550)","0","pure_quanta","I123";
;
PART_NUMBER"CS21002FB06"
MATERIAL"CHIP"
TOLERANCE"1%"
VALUE"1K"
$LOCATION"R1333"
CDS_LIB"pure_quanta"
PACK_TYPE"0402LF"
WATTAGE"1/16W"
CDS_LOCATION"R1333"
$SEC"1"
CDS_SEC"1";
"B"
$PN"2"27;
"A"
$PN"1"10;
%"UNIVERSAL_GND"
"1","(-975,1450)","0","logical_power","I124";
;
CDS_LIB"logical_power"
HDL_POWER"GND"
ROOM"IO_SLOT";
"A"10;
%"UNIVERSAL_POWER"
"1","(2900,2375)","0","logical_power","I126";
;
HDL_POWER"P3V3_RTC_AUX"
CDS_LIB"logical_power";
"A"5;
%"Q_RES"
"2","(2900,2050)","0","pure_quanta","I127";
;
PART_NUMBER"CS32002FB06"
PACK_TYPE"0402LF"
WATTAGE"1/16W"
TOLERANCE"1%"
VALUE"20K"
MATERIAL"CHIP"
$LOCATION"R1340"
CDS_LIB"pure_quanta"
CDS_LOCATION"R1340"
$SEC"1"
CDS_SEC"1";
"A"
$PN"1"5;
"B"
$PN"2"26;
%"Q_CAP"
"1","(3000,1125)","0","pure_quanta","I128";
;
PART_NUMBER"CH5104KEB02"
MATERIAL"X6S"
PACK_TYPE"C0402"
VALUE"1UF"
VOLTAGE"25V"
TOLERANCE"10%"
$LOCATION"C1177"
CDS_LIB"pure_quanta"
CDS_LOCATION"C1177"
$SEC"1"
CDS_SEC"1";
"B"
$PN"2"11;
"A"
$PN"1"26;
%"UNIVERSAL_GND"
"1","(3000,900)","0","logical_power","I129";
;
CDS_LIB"logical_power"
HDL_POWER"GND";
"A"11;
%"Q_RES"
"1","(-350,3450)","0","pure_quanta","I132";
;
PART_NUMBER"CS21002FB06"
TOLERANCE"1%"
VALUE"1K"
MATERIAL"CHIP"
$LOCATION"R3039"
WATTAGE"1/16W"
PACK_TYPE"0402LF"
CDS_LIB"pure_quanta"
CDS_LOCATION"R3039"
$SEC"1"
CDS_SEC"1";
"B"
$PN"2"13;
"A"
$PN"1"6;
%"Q_RES"
"1","(-350,3400)","0","pure_quanta","I133";
;
PART_NUMBER"CS21002FB06"
MATERIAL"CHIP"
PACK_TYPE"0402LF"
WATTAGE"1/16W"
TOLERANCE"1%"
VALUE"1K"
$LOCATION"R1335"
CDS_LIB"pure_quanta"
CDS_LOCATION"R1335"
$SEC"1"
CDS_SEC"1";
"B"
$PN"2"14;
"A"
$PN"1"6;
%"CONN14_210HP207GBR1"
"1","(1375,3550)","0","pure_quanta","I134";
;
PART_NUMBER"DFHD14MS170"
PART_TYPE"THLF"
MATERIAL"IO"
VALUE"CONN14_210-HP2-07GBR1"
LOCATION"J104"
CDS_LIB"pure_quanta"
NEEDS_NO_SIZE"TRUE"
CDS_LMAN_SYM_OUTLINE"-100,200,100,-200"
$SEC"1"
CDS_SEC"1";
"14"
$PN"14"19;
"13"
$PN"13"14;
"12"
$PN"12"20;
"11"
$PN"11"13;
"10"
$PN"10"25;
"9"
$PN"9"15;
"8"
$PN"8"24;
"7"
$PN"7"16;
"6"
$PN"6"23;
"5"
$PN"5"12;
"4"
$PN"4"22;
"3"
$PN"3"17;
"2"
$PN"2"21;
"1"
$PN"1"18;
%"Q_RES"
"1","(-350,3700)","0","pure_quanta","I86";
;
PART_NUMBER"CS21002FB06"
VALUE"1K"
MATERIAL"CHIP"
TOLERANCE"1%"
$LOCATION"R2133"
PACK_TYPE"0402LF"
WATTAGE"1/16W"
CDS_LIB"pure_quanta"
CDS_LOCATION"R2133"
$SEC"1"
CDS_SEC"1";
"B"
$PN"2"18;
"A"
$PN"1"2;
%"Q_RES"
"1","(-350,3550)","0","pure_quanta","I87";
;
PART_NUMBER"CS21002FB06"
VALUE"1K"
MATERIAL"CHIP"
$LOCATION"R1324"
WATTAGE"1/16W"
TOLERANCE"1%"
PACK_TYPE"0402LF"
CDS_LIB"pure_quanta"
CDS_LOCATION"R1324"
$SEC"1"
CDS_SEC"1";
"B"
$PN"2"16;
"A"
$PN"1"6;
%"Q_RES"
"1","(-350,3650)","0","pure_quanta","I88";
;
PART_NUMBER"CS21002FB06"
TOLERANCE"1%"
VALUE"1K"
MATERIAL"CHIP"
$LOCATION"R1317"
CDS_LIB"pure_quanta"
PACK_TYPE"0402LF"
WATTAGE"1/16W"
CDS_LOCATION"R1317"
$SEC"1"
CDS_SEC"1";
"B"
$PN"2"17;
"A"
$PN"1"1;
%"Q_RES"
"1","(-350,3600)","0","pure_quanta","I89";
;
PART_NUMBER"CS21002FB06"
VALUE"1K"
TOLERANCE"1%"
MATERIAL"CHIP"
$LOCATION"R1320"
CDS_LIB"pure_quanta"
WATTAGE"1/16W"
PACK_TYPE"0402LF"
CDS_LOCATION"R1320"
$SEC"1"
CDS_SEC"1";
"B"
$PN"2"12;
"A"
$PN"1"2;
%"UNIVERSAL_POWER"
"1","(-775,3925)","0","logical_power","I90";
;
HDL_POWER"P1V05_PCH_AUX"
CDS_LIB"logical_power";
"A"1;
%"UNIVERSAL_POWER"
"1","(-1200,3925)","0","logical_power","I92";
;
HDL_POWER"P3V3_AUX"
CDS_LIB"logical_power";
"A"2;
%"Q_RES"
"1","(-350,3500)","0","pure_quanta","I93";
;
PART_NUMBER"CS21002FB06"
MATERIAL"CHIP"
VALUE"1K"
TOLERANCE"1%"
$LOCATION"R1325"
CDS_LIB"pure_quanta"
PACK_TYPE"0402LF"
WATTAGE"1/16W"
CDS_LOCATION"R1325"
$SEC"1"
CDS_SEC"1";
"B"
$PN"2"15;
"A"
$PN"1"2;
%"UNIVERSAL_GND"
"1","(-775,3225)","0","logical_power","I98";
;
CDS_LIB"logical_power"
HDL_POWER"GND"
ROOM"IO_SLOT";
"A"6;
%"UNIVERSAL_POWER"
"1","(3575,4275)","0","logical_power","I99";
;
HDL_POWER"P3V3_AUX"
CDS_LIB"logical_power";
"A"3;
END.
